# ECP5 - Datacenter Secure Control Module (DC-SCM) — assets/stackup.csv
Name;Type;Material;Thickness[mm];Constant
F.Mask;Top Solder Mask;;0.01;
F.Cu;copper;;0.035;
dielectric 1;prepreg;PR2116;0.12;3.9
In1.Cu;copper;;0.035;
dielectric 2;core;FR4;0.2;3.9
In2.Cu;copper;;0.035;
dielectric 3;prepreg;PR2116;0.24;3.9
In3.Cu;copper;;0.035;
dielectric 4;core;PR2116;0.2;3.9
In4.Cu;copper;;0.035;
dielectric 5;prepreg;PR2116;0.24;3.9
In5.Cu;copper;;0.035;
dielectric 6;core;FR4;0.2;3.9
In6.Cu;copper;;0.035;
dielectric 7;prepreg;PR2116;0.12;3.9
B.Cu;copper;;0.035;
B.Mask;Bottom Solder Mask;;0.01;
